FILE_TYPE = CONNECTIVITY;
{Allegro Design Entry HDL 17.4-2019 S026 (4007227) 1/17/2022}
"PAGE_NUMBER" = 40;
0"NC";
1"M_D_CPU1_SA_DQ<31:0>";
2"M_D_CPU1_SB_DQ<31:0>";
3"M_D_CPU1_SA_CB<7:0>";
4"M_D_CPU1_SB_CB<7:0>";
5"M_D_CPU1_SA_DQS_DN<9:0>";
6"M_D_CPU1_SA_DQS_DP<9:0>";
7"M_D_CPU1_SB_DQS_DN<9:0>";
8"M_D_CPU1_SB_DQS_DP<9:0>";
9"M_D_CPU1_SA_CA<6:0>";
10"M_D_CPU1_SB_CA<6:0>";
11"M_D_CPU1_ALERT_N";
12"M_D_CPU1_ALERT_R_N";
13"TP_M_D_CPU1_SA_TEST39D";
14"M_D_CPU1_CLK_DP<0>";
15"M_D_CPU1_CLK_DN<0>";
16"M_D_CPU1_SA_CS_N<0>";
17"M_D_CPU1_SA_CS_N<1>";
18"M_D_CPU1_SA_RSP<0>";
19"M_D_CPU1_SA_PAR";
20"M_D_CPU1_SB_CS_N<0>";
21"M_D_CPU1_SB_CS_N<1>";
22"M_D_CPU1_SB_RSP<0>";
23"M_D_CPU1_SB_PAR";
24"M_D_CPU1_RESET_N";
25"M_D_CPU1_SB_DQS_DP<9>";
26"M_D_CPU1_SB_CA<3>";
27"M_D_CPU1_SB_CA<6>";
28"M_D_CPU1_SA_CA<6>";
29"M_D_CPU1_SB_CA<5>";
30"M_D_CPU1_SA_CA<5>";
31"M_D_CPU1_SB_CA<4>";
32"M_D_CPU1_SA_CA<4>";
33"M_D_CPU1_SB_DQS_DN<9>";
34"M_D_CPU1_SA_CA<3>";
35"M_D_CPU1_SB_CA<2>";
36"M_D_CPU1_SA_CA<2>";
37"M_D_CPU1_SB_CA<1>";
38"M_D_CPU1_SA_CA<1>";
39"M_D_CPU1_SB_CA<0>";
40"M_D_CPU1_SA_CA<0>";
41"M_D_CPU1_SB_DQS_DP<8>";
42"M_D_CPU1_SB_DQS_DP<7>";
43"M_D_CPU1_SB_DQS_DP<6>";
44"M_D_CPU1_SB_DQS_DP<5>";
45"M_D_CPU1_SB_DQS_DP<4>";
46"M_D_CPU1_SB_DQS_DN<8>";
47"M_D_CPU1_SB_DQS_DP<3>";
48"M_D_CPU1_SB_DQS_DN<7>";
49"M_D_CPU1_SB_DQS_DP<2>";
50"M_D_CPU1_SB_DQS_DN<6>";
51"M_D_CPU1_SB_DQS_DP<1>";
52"M_D_CPU1_SB_DQS_DN<5>";
53"M_D_CPU1_SB_DQS_DP<0>";
54"M_D_CPU1_SB_DQS_DN<4>";
55"M_D_CPU1_SA_DQS_DN<9>";
56"M_D_CPU1_SB_DQS_DN<3>";
57"M_D_CPU1_SB_DQS_DN<2>";
58"M_D_CPU1_SB_DQS_DN<1>";
59"M_D_CPU1_SB_DQS_DN<0>";
60"M_D_CPU1_SA_DQS_DP<0>";
61"M_D_CPU1_SA_DQS_DN<4>";
62"M_D_CPU1_SA_DQS_DN<3>";
63"M_D_CPU1_SA_DQS_DN<2>";
64"M_D_CPU1_SA_DQS_DN<1>";
65"M_D_CPU1_SA_DQS_DN<0>";
66"M_D_CPU1_SA_DQS_DP<9>";
67"M_D_CPU1_SA_DQS_DP<8>";
68"M_D_CPU1_SA_DQS_DP<7>";
69"M_D_CPU1_SA_DQS_DP<6>";
70"M_D_CPU1_SA_DQS_DP<5>";
71"M_D_CPU1_SA_DQS_DP<4>";
72"M_D_CPU1_SA_DQS_DN<8>";
73"M_D_CPU1_SA_DQS_DP<3>";
74"M_D_CPU1_SA_DQS_DN<7>";
75"M_D_CPU1_SA_DQS_DP<2>";
76"M_D_CPU1_SA_DQS_DN<6>";
77"M_D_CPU1_SA_DQS_DP<1>";
78"M_D_CPU1_SA_DQS_DN<5>";
79"M_D_CPU1_SB_CB<2>";
80"M_D_CPU1_SB_CB<1>";
81"M_D_CPU1_SB_CB<0>";
82"M_D_CPU1_SB_CB<7>";
83"M_D_CPU1_SB_CB<6>";
84"M_D_CPU1_SB_CB<5>";
85"M_D_CPU1_SB_CB<4>";
86"M_D_CPU1_SB_CB<3>";
87"M_D_CPU1_SB_DQ<22>";
88"M_D_CPU1_SA_CB<7>";
89"M_D_CPU1_SA_CB<6>";
90"M_D_CPU1_SB_DQ<31>";
91"M_D_CPU1_SA_CB<5>";
92"M_D_CPU1_SB_DQ<30>";
93"M_D_CPU1_SA_CB<4>";
94"M_D_CPU1_SA_CB<3>";
95"M_D_CPU1_SA_CB<2>";
96"M_D_CPU1_SA_CB<1>";
97"M_D_CPU1_SA_CB<0>";
98"M_D_CPU1_SB_DQ<29>";
99"M_D_CPU1_SB_DQ<28>";
100"M_D_CPU1_SB_DQ<27>";
101"M_D_CPU1_SB_DQ<26>";
102"M_D_CPU1_SB_DQ<25>";
103"M_D_CPU1_SB_DQ<24>";
104"M_D_CPU1_SB_DQ<23>";
105"M_D_CPU1_SB_DQ<11>";
106"M_D_CPU1_SB_DQ<10>";
107"M_D_CPU1_SB_DQ<21>";
108"M_D_CPU1_SB_DQ<20>";
109"M_D_CPU1_SB_DQ<9>";
110"M_D_CPU1_SB_DQ<19>";
111"M_D_CPU1_SB_DQ<8>";
112"M_D_CPU1_SB_DQ<18>";
113"M_D_CPU1_SB_DQ<7>";
114"M_D_CPU1_SB_DQ<17>";
115"M_D_CPU1_SB_DQ<6>";
116"M_D_CPU1_SB_DQ<16>";
117"M_D_CPU1_SB_DQ<5>";
118"M_D_CPU1_SB_DQ<15>";
119"M_D_CPU1_SB_DQ<4>";
120"M_D_CPU1_SB_DQ<14>";
121"M_D_CPU1_SB_DQ<3>";
122"M_D_CPU1_SB_DQ<13>";
123"M_D_CPU1_SB_DQ<12>";
124"M_D_CPU1_SA_DQ<17>";
125"M_D_CPU1_SA_DQ<28>";
126"M_D_CPU1_SB_DQ<1>";
127"M_D_CPU1_SA_DQ<27>";
128"M_D_CPU1_SB_DQ<0>";
129"M_D_CPU1_SA_DQ<26>";
130"M_D_CPU1_SA_DQ<25>";
131"M_D_CPU1_SA_DQ<24>";
132"M_D_CPU1_SA_DQ<23>";
133"M_D_CPU1_SA_DQ<22>";
134"M_D_CPU1_SA_DQ<21>";
135"M_D_CPU1_SA_DQ<20>";
136"M_D_CPU1_SA_DQ<31>";
137"M_D_CPU1_SA_DQ<30>";
138"M_D_CPU1_SA_DQ<19>";
139"M_D_CPU1_SA_DQ<18>";
140"M_D_CPU1_SA_DQ<29>";
141"M_D_CPU1_SB_DQ<2>";
142"M_D_CPU1_SA_DQ<2>";
143"M_D_CPU1_SA_DQ<1>";
144"M_D_CPU1_SA_DQ<16>";
145"M_D_CPU1_SA_DQ<0>";
146"M_D_CPU1_SA_DQ<15>";
147"M_D_CPU1_SA_DQ<14>";
148"M_D_CPU1_SA_DQ<13>";
149"M_D_CPU1_SA_DQ<12>";
150"M_D_CPU1_SA_DQ<11>";
151"M_D_CPU1_SA_DQ<10>";
152"M_D_CPU1_SA_DQ<9>";
153"M_D_CPU1_SA_DQ<8>";
154"M_D_CPU1_SA_DQ<7>";
155"M_D_CPU1_SA_DQ<6>";
156"M_D_CPU1_SA_DQ<5>";
157"M_D_CPU1_SA_DQ<4>";
158"M_D_CPU1_SA_DQ<3>";
%"GENOA_SP5"
"4","(-4600,3650)","0","pure_quanta","I159";
;
LOCATION"U26"
$SEC"4"
CDS_SEC"4"
PART_TYPE"SMLF"
MATERIAL"IO"
VALUE"SOCKET6096_13568-001"
CDS_LIB"pure_quanta"
CDS_LMAN_SYM_OUTLINE"-650,2525,650,-2525"
NEEDS_NO_SIZE"TRUE"
PART_NUMBER"DGA^6000030";
"TEST39D"
$PN"BF58"13;
"MD1_CLK_L"
$PN"BG60"0;
"MD1_CLK_H"
$PN"BF60"0;
"MD0_CLK_L"
$PN"BD60"15;
"MD0_CLK_H"
$PN"BC60"14;
"MDB_DQS_H9"
$PN"BV60"25;
"MDB_CA3"
$PN"BJ60"26;
"MDB_PAR"
$PN"BL60"23;
"MDA_PAR"
$PN"BC59"19;
"MDA1_RSP_L"
$PN"BP58"0;
"MDA_DATA2"
$PN"F60"142;
"MDA_DATA17"
$PN"V58"124;
"MDA_DATA28"
$PN"AG60"125;
"MDA_DQS_H0"
$PN"G60"60;
"MDA_DQS_L4"
$PN"AM60"61;
"MDB_CHECK2"
$PN"CA60"79;
"MDB_DATA1"
$PN"CC59"126;
"MDB_DATA11"
$PN"CK58"105;
"MDB_DATA22"
$PN"CW60"87;
"MDA0_RSP_L"
$PN"BN59"18;
"MDA_CHECK7"
$PN"AR59"88;
"MDA_DATA1"
$PN"F58"143;
"MDA_DATA16"
$PN"U60"144;
"MDA_DATA27"
$PN"AE59"127;
"MDA_DQS_L3"
$PN"AF60"62;
"MDB_CHECK1"
$PN"CA59"80;
"MDB_DATA0"
$PN"CB60"128;
"MDB_DATA10"
$PN"CJ60"106;
"MDB_DATA21"
$PN"CW59"107;
"MDA_CHECK6"
$PN"AP60"89;
"MDA_DATA0"
$PN"E60"145;
"MDA_DATA15"
$PN"U59"146;
"MDA_DATA26"
$PN"AD60"129;
"MDA_DQS_L2"
$PN"Y60"63;
"MDB1_CS_L1"
$PN"BM60"0;
"MDB_CHECK0"
$PN"BY60"81;
"MDB_DATA20"
$PN"CV60"108;
"MDB_DATA31"
$PN"DF60"90;
"MDA_CHECK5"
$PN"AP58"91;
"MDA_DATA14"
$PN"T60"147;
"MDA_DATA25"
$PN"AD58"130;
"MDA_DQS_L1"
$PN"P60"64;
"MDB0_CS_L1"
$PN"BN60"21;
"MDB1_CS_L0"
$PN"BL59"0;
"MDB_CA6"
$PN"BK60"27;
"MDB_DATA30"
$PN"DE60"92;
"MDB_DQS_H8"
$PN"DD58"41;
"MDA_CA6"
$PN"BB58"28;
"MDA_CHECK4"
$PN"AN60"93;
"MDA_DATA13"
$PN"T58"148;
"MDA_DATA24"
$PN"AC60"131;
"MDA_DQS_L0"
$PN"H60"65;
"MDB0_CS_L0"
$PN"BM58"20;
"MDB_CA5"
$PN"BK58"29;
"MDB_DQS_H7"
$PN"CV58"42;
"MDA_CA5"
$PN"BB60"30;
"MDA_CHECK3"
$PN"AL59"94;
"MDA_DATA12"
$PN"R60"149;
"MDA_DATA23"
$PN"AC59"132;
"MDB_CA4"
$PN"BJ59"31;
"MDB_DQS_H6"
$PN"CM58"43;
"MDA_CA4"
$PN"BA60"32;
"MDA_CHECK2"
$PN"AK60"95;
"MDA_DATA11"
$PN"N59"150;
"MDA_DATA22"
$PN"AB60"133;
"MDB_DQS_H5"
$PN"CF58"44;
"MDB_DQS_L9"
$PN"BW60"33;
"MDA_CA3"
$PN"BA59"34;
"MDA_CHECK1"
$PN"AK58"96;
"MDA_DATA10"
$PN"M60"151;
"MDA_DATA21"
$PN"AB58"134;
"MDB_CA2"
$PN"BH60"35;
"MDB_DQS_H4"
$PN"BY58"45;
"MDB_DQS_L8"
$PN"DC59"46;
"MDA1_CS_L1"
$PN"AV58"0;
"MDA_CA2"
$PN"AY58"36;
"MDA_CHECK0"
$PN"AJ60"97;
"MDA_DATA20"
$PN"AA60"135;
"MDA_DATA31"
$PN"AJ59"136;
"MDA_DQS_H9"
$PN"AN59"66;
"MDB_CA1"
$PN"BH58"37;
"MDB_DQS_H3"
$PN"DB60"47;
"MDB_DQS_L7"
$PN"CU59"48;
"MDA0_CS_L1"
$PN"AW59"17;
"MDA1_CS_L0"
$PN"AU60"0;
"MDA_CA1"
$PN"AY60"38;
"MDA_DATA30"
$PN"AH60"137;
"MDA_DQS_H8"
$PN"AG59"67;
"MDB_CA0"
$PN"BG59"39;
"MDB_DATA9"
$PN"CJ59"109;
"MDB_DATA19"
$PN"CT58"110;
"MDB_DQS_H2"
$PN"CT60"49;
"MDB_DQS_L6"
$PN"CL59"50;
"MDA0_CS_L0"
$PN"AV60"16;
"MDA_CA0"
$PN"AW60"40;
"MDA_DATA9"
$PN"M58"152;
"MDA_DQS_H7"
$PN"AA59"68;
"MDB_DATA8"
$PN"CH60"111;
"MDB_DATA18"
$PN"CR60"112;
"MDB_DATA29"
$PN"DE59"98;
"MDB_DQS_H1"
$PN"CK60"51;
"MDB_DQS_L5"
$PN"CE59"52;
"MDA_DATA8"
$PN"L60"153;
"MDA_DQS_H6"
$PN"R59"69;
"MDB1_RSP_L"
$PN"BR60"0;
"MDB_DATA7"
$PN"CH58"113;
"MDB_DATA17"
$PN"CR59"114;
"MDB_DATA28"
$PN"DD60"99;
"MDB_DQS_H0"
$PN"CD60"53;
"MDB_DQS_L4"
$PN"BW59"54;
"MDA_DATA7"
$PN"L59"154;
"MDA_DQS_H5"
$PN"J59"70;
"MDA_DQS_L9"
$PN"AM58"55;
"MDB0_RSP_L"
$PN"BP60"22;
"MDB_CHECK7"
$PN"BV58"82;
"MDB_DATA6"
$PN"CG60"115;
"MDB_DATA16"
$PN"CP60"116;
"MDB_DATA27"
$PN"DB58"100;
"MDB_DQS_L3"
$PN"DC60"56;
"MDA_DATA6"
$PN"K60"155;
"MDA_DQS_H4"
$PN"AL60"71;
"MDA_DQS_L8"
$PN"AF58"72;
"MDB_CHECK6"
$PN"BU60"83;
"MDB_DATA5"
$PN"CG59"117;
"MDB_DATA15"
$PN"CP58"118;
"MDB_DATA26"
$PN"DA60"101;
"MDB_DQS_L2"
$PN"CU60"57;
"MDA_DATA5"
$PN"K58"156;
"MDA_DQS_H3"
$PN"AE60"73;
"MDA_DQS_L7"
$PN"Y58"74;
"MDB_CHECK5"
$PN"BU59"84;
"MDB_DATA4"
$PN"CF60"119;
"MDB_DATA14"
$PN"CN60"120;
"MDB_DATA25"
$PN"DA59"102;
"MDB_DQS_L1"
$PN"CL60"58;
"MDA_DATA4"
$PN"J60"157;
"MDA_DATA19"
$PN"W59"138;
"MDA_DQS_H2"
$PN"W60"75;
"MDA_DQS_L6"
$PN"P58"76;
"MDB_CHECK4"
$PN"BT60"85;
"MDB_DATA3"
$PN"CD58"121;
"MDB_DATA13"
$PN"CN59"122;
"MDB_DATA24"
$PN"CY60"103;
"MDB_DQS_L0"
$PN"CE60"59;
"MDA_DATA3"
$PN"G59"158;
"MDA_DATA18"
$PN"V60"139;
"MDA_DATA29"
$PN"AH58"140;
"MDA_DQS_H1"
$PN"N60"77;
"MDA_DQS_L5"
$PN"H58"78;
"MDB_CHECK3"
$PN"CB58"86;
"MDB_DATA2"
$PN"CC60"141;
"MDB_DATA12"
$PN"CM60"123;
"MDB_DATA23"
$PN"CY58"104;
"MD_RESET_L"
$PN"AU59"24;
"MD_ALERT_L"
$PN"AT58"12;
%"TAP"
"1","(-3325,5975)","0","mstr_standard","I162";
;
CDS_LIB"mstr_standard"
BODY_TYPE"PLUMBING"
HDL_TAP"TRUE";
"B \NAC \NWC"1;
"S \NAC"
BN"1"143;
%"TAP"
"1","(-3325,5925)","0","mstr_standard","I163";
;
CDS_LIB"mstr_standard"
BODY_TYPE"PLUMBING"
HDL_TAP"TRUE";
"B \NAC \NWC"1;
"S \NAC"
BN"2"142;
%"TAP"
"1","(-3325,6025)","0","mstr_standard","I164";
;
CDS_LIB"mstr_standard"
BODY_TYPE"PLUMBING"
HDL_TAP"TRUE";
"B \NAC \NWC"1;
"S \NAC"
BN"0"145;
%"TAP"
"1","(-3325,5825)","0","mstr_standard","I165";
;
CDS_LIB"mstr_standard"
BODY_TYPE"PLUMBING"
HDL_TAP"TRUE";
"B \NAC \NWC"1;
"S \NAC"
BN"4"157;
%"TAP"
"1","(-3325,5875)","0","mstr_standard","I166";
;
CDS_LIB"mstr_standard"
BODY_TYPE"PLUMBING"
HDL_TAP"TRUE";
"B \NAC \NWC"1;
"S \NAC"
BN"3"158;
%"TAP"
"1","(-3325,5775)","0","mstr_standard","I167";
;
CDS_LIB"mstr_standard"
BODY_TYPE"PLUMBING"
HDL_TAP"TRUE";
"B \NAC \NWC"1;
"S \NAC"
BN"5"156;
%"TAP"
"1","(-3325,5725)","0","mstr_standard","I168";
;
CDS_LIB"mstr_standard"
BODY_TYPE"PLUMBING"
HDL_TAP"TRUE";
"B \NAC \NWC"1;
"S \NAC"
BN"6"155;
%"TAP"
"1","(-3325,5675)","0","mstr_standard","I169";
;
CDS_LIB"mstr_standard"
BODY_TYPE"PLUMBING"
HDL_TAP"TRUE";
"B \NAC \NWC"1;
"S \NAC"
BN"7"154;
%"TAP"
"1","(-3325,5425)","0","mstr_standard","I170";
;
CDS_LIB"mstr_standard"
BODY_TYPE"PLUMBING"
HDL_TAP"TRUE";
"B \NAC \NWC"1;
"S \NAC"
BN"11"150;
%"TAP"
"1","(-3325,5475)","0","mstr_standard","I171";
;
CDS_LIB"mstr_standard"
BODY_TYPE"PLUMBING"
HDL_TAP"TRUE";
"B \NAC \NWC"1;
"S \NAC"
BN"10"151;
%"TAP"
"1","(-3325,5525)","0","mstr_standard","I172";
;
CDS_LIB"mstr_standard"
BODY_TYPE"PLUMBING"
HDL_TAP"TRUE";
"B \NAC \NWC"1;
"S \NAC"
BN"9"152;
%"TAP"
"1","(-3325,5575)","0","mstr_standard","I173";
;
CDS_LIB"mstr_standard"
BODY_TYPE"PLUMBING"
HDL_TAP"TRUE";
"B \NAC \NWC"1;
"S \NAC"
BN"8"153;
%"TAP"
"1","(-3325,5125)","0","mstr_standard","I174";
;
CDS_LIB"mstr_standard"
BODY_TYPE"PLUMBING"
HDL_TAP"TRUE";
"B \NAC \NWC"1;
"S \NAC"
BN"16"144;
%"TAP"
"1","(-3325,5225)","0","mstr_standard","I175";
;
CDS_LIB"mstr_standard"
BODY_TYPE"PLUMBING"
HDL_TAP"TRUE";
"B \NAC \NWC"1;
"S \NAC"
BN"15"146;
%"TAP"
"1","(-3325,5275)","0","mstr_standard","I176";
;
CDS_LIB"mstr_standard"
BODY_TYPE"PLUMBING"
HDL_TAP"TRUE";
"B \NAC \NWC"1;
"S \NAC"
BN"14"147;
%"TAP"
"1","(-3325,5375)","0","mstr_standard","I177";
;
CDS_LIB"mstr_standard"
BODY_TYPE"PLUMBING"
HDL_TAP"TRUE";
"B \NAC \NWC"1;
"S \NAC"
BN"12"149;
%"TAP"
"1","(-3325,5325)","0","mstr_standard","I178";
;
CDS_LIB"mstr_standard"
BODY_TYPE"PLUMBING"
HDL_TAP"TRUE";
"B \NAC \NWC"1;
"S \NAC"
BN"13"148;
%"TAP"
"1","(-3325,4925)","0","mstr_standard","I179";
;
CDS_LIB"mstr_standard"
BODY_TYPE"PLUMBING"
HDL_TAP"TRUE";
"B \NAC \NWC"1;
"S \NAC"
BN"20"135;
%"TAP"
"1","(-3325,4875)","0","mstr_standard","I180";
;
CDS_LIB"mstr_standard"
BODY_TYPE"PLUMBING"
HDL_TAP"TRUE";
"B \NAC \NWC"1;
"S \NAC"
BN"21"134;
%"TAP"
"1","(-3325,4975)","0","mstr_standard","I181";
;
CDS_LIB"mstr_standard"
BODY_TYPE"PLUMBING"
HDL_TAP"TRUE";
"B \NAC \NWC"1;
"S \NAC"
BN"19"138;
%"TAP"
"1","(-3325,5025)","0","mstr_standard","I182";
;
CDS_LIB"mstr_standard"
BODY_TYPE"PLUMBING"
HDL_TAP"TRUE";
"B \NAC \NWC"1;
"S \NAC"
BN"18"139;
%"TAP"
"1","(-3325,5075)","0","mstr_standard","I183";
;
CDS_LIB"mstr_standard"
BODY_TYPE"PLUMBING"
HDL_TAP"TRUE";
"B \NAC \NWC"1;
"S \NAC"
BN"17"124;
%"TAP"
"1","(-3325,4825)","0","mstr_standard","I184";
;
CDS_LIB"mstr_standard"
BODY_TYPE"PLUMBING"
HDL_TAP"TRUE";
"B \NAC \NWC"1;
"S \NAC"
BN"22"133;
%"TAP"
"1","(-3325,4775)","0","mstr_standard","I185";
;
CDS_LIB"mstr_standard"
BODY_TYPE"PLUMBING"
HDL_TAP"TRUE";
"B \NAC \NWC"1;
"S \NAC"
BN"23"132;
%"TAP"
"1","(-3325,4675)","0","mstr_standard","I186";
;
CDS_LIB"mstr_standard"
BODY_TYPE"PLUMBING"
HDL_TAP"TRUE";
"B \NAC \NWC"1;
"S \NAC"
BN"24"131;
%"TAP"
"1","(-3325,4625)","0","mstr_standard","I187";
;
CDS_LIB"mstr_standard"
BODY_TYPE"PLUMBING"
HDL_TAP"TRUE";
"B \NAC \NWC"1;
"S \NAC"
BN"25"130;
%"TAP"
"1","(-3325,4425)","0","mstr_standard","I188";
;
CDS_LIB"mstr_standard"
BODY_TYPE"PLUMBING"
HDL_TAP"TRUE";
"B \NAC \NWC"1;
"S \NAC"
BN"29"140;
%"TAP"
"1","(-3325,4375)","0","mstr_standard","I189";
;
CDS_LIB"mstr_standard"
BODY_TYPE"PLUMBING"
HDL_TAP"TRUE";
"B \NAC \NWC"1;
"S \NAC"
BN"30"137;
%"TAP"
"1","(-3325,4475)","0","mstr_standard","I190";
;
CDS_LIB"mstr_standard"
BODY_TYPE"PLUMBING"
HDL_TAP"TRUE";
"B \NAC \NWC"1;
"S \NAC"
BN"28"125;
%"TAP"
"1","(-3325,4575)","0","mstr_standard","I191";
;
CDS_LIB"mstr_standard"
BODY_TYPE"PLUMBING"
HDL_TAP"TRUE";
"B \NAC \NWC"1;
"S \NAC"
BN"26"129;
%"TAP"
"1","(-3325,4525)","0","mstr_standard","I192";
;
CDS_LIB"mstr_standard"
BODY_TYPE"PLUMBING"
HDL_TAP"TRUE";
"B \NAC \NWC"1;
"S \NAC"
BN"27"127;
%"TAP"
"1","(-3325,4175)","0","mstr_standard","I193";
;
CDS_LIB"mstr_standard"
BODY_TYPE"PLUMBING"
HDL_TAP"TRUE";
"B \NAC \NWC"2;
"S \NAC"
BN"1"126;
%"TAP"
"1","(-3325,4325)","0","mstr_standard","I194";
;
CDS_LIB"mstr_standard"
BODY_TYPE"PLUMBING"
HDL_TAP"TRUE";
"B \NAC \NWC"1;
"S \NAC"
BN"31"136;
%"TAP"
"1","(-3325,4125)","0","mstr_standard","I195";
;
CDS_LIB"mstr_standard"
BODY_TYPE"PLUMBING"
HDL_TAP"TRUE";
"B \NAC \NWC"2;
"S \NAC"
BN"2"141;
%"TAP"
"1","(-3325,4225)","0","mstr_standard","I196";
;
CDS_LIB"mstr_standard"
BODY_TYPE"PLUMBING"
HDL_TAP"TRUE";
"B \NAC \NWC"2;
"S \NAC"
BN"0"128;
%"TAP"
"1","(-3325,4025)","0","mstr_standard","I198";
;
CDS_LIB"mstr_standard"
BODY_TYPE"PLUMBING"
HDL_TAP"TRUE";
"B \NAC \NWC"2;
"S \NAC"
BN"4"119;
%"TAP"
"1","(-3325,4075)","0","mstr_standard","I199";
;
CDS_LIB"mstr_standard"
BODY_TYPE"PLUMBING"
HDL_TAP"TRUE";
"B \NAC \NWC"2;
"S \NAC"
BN"3"121;
%"TAP"
"1","(-3325,3975)","0","mstr_standard","I200";
;
CDS_LIB"mstr_standard"
BODY_TYPE"PLUMBING"
HDL_TAP"TRUE";
"B \NAC \NWC"2;
"S \NAC"
BN"5"117;
%"TAP"
"1","(-3325,3925)","0","mstr_standard","I201";
;
CDS_LIB"mstr_standard"
BODY_TYPE"PLUMBING"
HDL_TAP"TRUE";
"B \NAC \NWC"2;
"S \NAC"
BN"6"115;
%"TAP"
"1","(-3325,3875)","0","mstr_standard","I202";
;
CDS_LIB"mstr_standard"
BODY_TYPE"PLUMBING"
HDL_TAP"TRUE";
"B \NAC \NWC"2;
"S \NAC"
BN"7"113;
%"TAP"
"1","(-3325,3625)","0","mstr_standard","I203";
;
CDS_LIB"mstr_standard"
BODY_TYPE"PLUMBING"
HDL_TAP"TRUE";
"B \NAC \NWC"2;
"S \NAC"
BN"11"105;
%"TAP"
"1","(-3325,3675)","0","mstr_standard","I204";
;
CDS_LIB"mstr_standard"
BODY_TYPE"PLUMBING"
HDL_TAP"TRUE";
"B \NAC \NWC"2;
"S \NAC"
BN"10"106;
%"TAP"
"1","(-3325,3775)","0","mstr_standard","I205";
;
CDS_LIB"mstr_standard"
BODY_TYPE"PLUMBING"
HDL_TAP"TRUE";
"B \NAC \NWC"2;
"S \NAC"
BN"8"111;
%"TAP"
"1","(-3325,3725)","0","mstr_standard","I206";
;
CDS_LIB"mstr_standard"
BODY_TYPE"PLUMBING"
HDL_TAP"TRUE";
"B \NAC \NWC"2;
"S \NAC"
BN"9"109;
%"TAP"
"1","(-3325,3425)","0","mstr_standard","I207";
;
CDS_LIB"mstr_standard"
BODY_TYPE"PLUMBING"
HDL_TAP"TRUE";
"B \NAC \NWC"2;
"S \NAC"
BN"15"118;
%"TAP"
"1","(-3325,3475)","0","mstr_standard","I208";
;
CDS_LIB"mstr_standard"
BODY_TYPE"PLUMBING"
HDL_TAP"TRUE";
"B \NAC \NWC"2;
"S \NAC"
BN"14"120;
%"TAP"
"1","(-3325,3575)","0","mstr_standard","I209";
;
CDS_LIB"mstr_standard"
BODY_TYPE"PLUMBING"
HDL_TAP"TRUE";
"B \NAC \NWC"2;
"S \NAC"
BN"12"123;
%"TAP"
"1","(-3325,3525)","0","mstr_standard","I210";
;
CDS_LIB"mstr_standard"
BODY_TYPE"PLUMBING"
HDL_TAP"TRUE";
"B \NAC \NWC"2;
"S \NAC"
BN"13"122;
%"TAP"
"1","(-3325,3325)","0","mstr_standard","I211";
;
CDS_LIB"mstr_standard"
BODY_TYPE"PLUMBING"
HDL_TAP"TRUE";
"B \NAC \NWC"2;
"S \NAC"
BN"16"116;
%"TAP"
"1","(-3325,3275)","0","mstr_standard","I212";
;
CDS_LIB"mstr_standard"
BODY_TYPE"PLUMBING"
HDL_TAP"TRUE";
"B \NAC \NWC"2;
"S \NAC"
BN"17"114;
%"TAP"
"1","(-3325,3225)","0","mstr_standard","I213";
;
CDS_LIB"mstr_standard"
BODY_TYPE"PLUMBING"
HDL_TAP"TRUE";
"B \NAC \NWC"2;
"S \NAC"
BN"18"112;
%"TAP"
"1","(-3325,3075)","0","mstr_standard","I214";
;
CDS_LIB"mstr_standard"
BODY_TYPE"PLUMBING"
HDL_TAP"TRUE";
"B \NAC \NWC"2;
"S \NAC"
BN"21"107;
%"TAP"
"1","(-3325,3175)","0","mstr_standard","I215";
;
CDS_LIB"mstr_standard"
BODY_TYPE"PLUMBING"
HDL_TAP"TRUE";
"B \NAC \NWC"2;
"S \NAC"
BN"19"110;
%"TAP"
"1","(-3325,3125)","0","mstr_standard","I216";
;
CDS_LIB"mstr_standard"
BODY_TYPE"PLUMBING"
HDL_TAP"TRUE";
"B \NAC \NWC"2;
"S \NAC"
BN"20"108;
%"TAP"
"1","(-3325,2875)","0","mstr_standard","I217";
;
CDS_LIB"mstr_standard"
BODY_TYPE"PLUMBING"
HDL_TAP"TRUE";
"B \NAC \NWC"2;
"S \NAC"
BN"24"103;
%"TAP"
"1","(-3325,2975)","0","mstr_standard","I218";
;
CDS_LIB"mstr_standard"
BODY_TYPE"PLUMBING"
HDL_TAP"TRUE";
"B \NAC \NWC"2;
"S \NAC"
BN"23"104;
%"TAP"
"1","(-3325,3025)","0","mstr_standard","I219";
;
CDS_LIB"mstr_standard"
BODY_TYPE"PLUMBING"
HDL_TAP"TRUE";
"B \NAC \NWC"2;
"S \NAC"
BN"22"87;
%"TAP"
"1","(-3325,2825)","0","mstr_standard","I220";
;
CDS_LIB"mstr_standard"
BODY_TYPE"PLUMBING"
HDL_TAP"TRUE";
"B \NAC \NWC"2;
"S \NAC"
BN"25"102;
%"TAP"
"1","(-3325,2625)","0","mstr_standard","I221";
;
CDS_LIB"mstr_standard"
BODY_TYPE"PLUMBING"
HDL_TAP"TRUE";
"B \NAC \NWC"2;
"S \NAC"
BN"29"98;
%"TAP"
"1","(-3325,2575)","0","mstr_standard","I222";
;
CDS_LIB"mstr_standard"
BODY_TYPE"PLUMBING"
HDL_TAP"TRUE";
"B \NAC \NWC"2;
"S \NAC"
BN"30"92;
%"TAP"
"1","(-3325,2675)","0","mstr_standard","I223";
;
CDS_LIB"mstr_standard"
BODY_TYPE"PLUMBING"
HDL_TAP"TRUE";
"B \NAC \NWC"2;
"S \NAC"
BN"28"99;
%"TAP"
"1","(-3325,2775)","0","mstr_standard","I224";
;
CDS_LIB"mstr_standard"
BODY_TYPE"PLUMBING"
HDL_TAP"TRUE";
"B \NAC \NWC"2;
"S \NAC"
BN"26"101;
%"TAP"
"1","(-3325,2725)","0","mstr_standard","I225";
;
CDS_LIB"mstr_standard"
BODY_TYPE"PLUMBING"
HDL_TAP"TRUE";
"B \NAC \NWC"2;
"S \NAC"
BN"27"100;
%"TAP"
"1","(-3325,2525)","0","mstr_standard","I226";
;
CDS_LIB"mstr_standard"
BODY_TYPE"PLUMBING"
HDL_TAP"TRUE";
"B \NAC \NWC"2;
"S \NAC"
BN"31"90;
%"TAP"
"1","(-3325,2425)","0","mstr_standard","I227";
;
CDS_LIB"mstr_standard"
BODY_TYPE"PLUMBING"
HDL_TAP"TRUE";
"B \NAC \NWC"3;
"S \NAC"
BN"0"97;
%"TAP"
"1","(-3325,2325)","0","mstr_standard","I228";
;
CDS_LIB"mstr_standard"
BODY_TYPE"PLUMBING"
HDL_TAP"TRUE";
"B \NAC \NWC"3;
"S \NAC"
BN"2"95;
%"TAP"
"1","(-3325,2375)","0","mstr_standard","I229";
;
CDS_LIB"mstr_standard"
BODY_TYPE"PLUMBING"
HDL_TAP"TRUE";
"B \NAC \NWC"3;
"S \NAC"
BN"1"96;
%"TAP"
"1","(-3325,2275)","0","mstr_standard","I230";
;
CDS_LIB"mstr_standard"
BODY_TYPE"PLUMBING"
HDL_TAP"TRUE";
"B \NAC \NWC"3;
"S \NAC"
BN"3"94;
%"TAP"
"1","(-3325,2225)","0","mstr_standard","I231";
;
CDS_LIB"mstr_standard"
BODY_TYPE"PLUMBING"
HDL_TAP"TRUE";
"B \NAC \NWC"3;
"S \NAC"
BN"4"93;
%"TAP"
"1","(-3325,2175)","0","mstr_standard","I232";
;
CDS_LIB"mstr_standard"
BODY_TYPE"PLUMBING"
HDL_TAP"TRUE";
"B \NAC \NWC"3;
"S \NAC"
BN"5"91;
%"TAP"
"1","(-3325,2125)","0","mstr_standard","I233";
;
CDS_LIB"mstr_standard"
BODY_TYPE"PLUMBING"
HDL_TAP"TRUE";
"B \NAC \NWC"3;
"S \NAC"
BN"6"89;
%"TAP"
"1","(-3325,2075)","0","mstr_standard","I234";
;
CDS_LIB"mstr_standard"
BODY_TYPE"PLUMBING"
HDL_TAP"TRUE";
"B \NAC \NWC"3;
"S \NAC"
BN"7"88;
%"TAP"
"1","(-3325,1925)","0","mstr_standard","I236";
;
CDS_LIB"mstr_standard"
BODY_TYPE"PLUMBING"
HDL_TAP"TRUE";
"B \NAC \NWC"4;
"S \NAC"
BN"1"80;
%"TAP"
"1","(-3325,1975)","0","mstr_standard","I237";
;
CDS_LIB"mstr_standard"
BODY_TYPE"PLUMBING"
HDL_TAP"TRUE";
"B \NAC \NWC"4;
"S \NAC"
BN"0"81;
%"TAP"
"1","(-3325,1825)","0","mstr_standard","I238";
;
CDS_LIB"mstr_standard"
BODY_TYPE"PLUMBING"
HDL_TAP"TRUE";
"B \NAC \NWC"4;
"S \NAC"
BN"3"86;
%"TAP"
"1","(-3325,1875)","0","mstr_standard","I239";
;
CDS_LIB"mstr_standard"
BODY_TYPE"PLUMBING"
HDL_TAP"TRUE";
"B \NAC \NWC"4;
"S \NAC"
BN"2"79;
%"TAP"
"1","(-3325,1625)","0","mstr_standard","I240";
;
CDS_LIB"mstr_standard"
BODY_TYPE"PLUMBING"
HDL_TAP"TRUE";
"B \NAC \NWC"4;
"S \NAC"
BN"7"82;
%"TAP"
"1","(-3325,1675)","0","mstr_standard","I241";
;
CDS_LIB"mstr_standard"
BODY_TYPE"PLUMBING"
HDL_TAP"TRUE";
"B \NAC \NWC"4;
"S \NAC"
BN"6"83;
%"TAP"
"1","(-3325,1775)","0","mstr_standard","I242";
;
CDS_LIB"mstr_standard"
BODY_TYPE"PLUMBING"
HDL_TAP"TRUE";
"B \NAC \NWC"4;
"S \NAC"
BN"4"85;
%"TAP"
"1","(-3325,1725)","0","mstr_standard","I243";
;
CDS_LIB"mstr_standard"
BODY_TYPE"PLUMBING"
HDL_TAP"TRUE";
"B \NAC \NWC"4;
"S \NAC"
BN"5"84;
%"TAP"
"1","(-5750,6025)","2","mstr_standard","I244";
;
CDS_LIB"mstr_standard"
BODY_TYPE"PLUMBING"
HDL_TAP"TRUE";
"B \NAC \NWC"6;
"S \NAC"
BN"0"60;
%"TAP"
"1","(-5750,5925)","2","mstr_standard","I245";
;
CDS_LIB"mstr_standard"
BODY_TYPE"PLUMBING"
HDL_TAP"TRUE";
"B \NAC \NWC"6;
"S \NAC"
BN"1"77;
%"TAP"
"1","(-5750,5825)","2","mstr_standard","I246";
;
CDS_LIB"mstr_standard"
BODY_TYPE"PLUMBING"
HDL_TAP"TRUE";
"B \NAC \NWC"6;
"S \NAC"
BN"2"75;
%"TAP"
"1","(-5750,5725)","2","mstr_standard","I247";
;
CDS_LIB"mstr_standard"
BODY_TYPE"PLUMBING"
HDL_TAP"TRUE";
"B \NAC \NWC"6;
"S \NAC"
BN"3"73;
%"TAP"
"1","(-5950,5975)","2","mstr_standard","I248";
;
CDS_LIB"mstr_standard"
BODY_TYPE"PLUMBING"
HDL_TAP"TRUE";
"B \NAC \NWC"5;
"S \NAC"
BN"0"65;
%"TAP"
"1","(-5950,5875)","2","mstr_standard","I249";
;
CDS_LIB"mstr_standard"
BODY_TYPE"PLUMBING"
HDL_TAP"TRUE";
"B \NAC \NWC"5;
"S \NAC"
BN"1"64;
%"TAP"
"1","(-5950,5775)","2","mstr_standard","I250";
;
CDS_LIB"mstr_standard"
BODY_TYPE"PLUMBING"
HDL_TAP"TRUE";
"B \NAC \NWC"5;
"S \NAC"
BN"2"63;
%"TAP"
"1","(-5950,5675)","2","mstr_standard","I251";
;
CDS_LIB"mstr_standard"
BODY_TYPE"PLUMBING"
HDL_TAP"TRUE";
"B \NAC \NWC"5;
"S \NAC"
BN"3"62;
%"TAP"
"1","(-5750,5625)","2","mstr_standard","I252";
;
CDS_LIB"mstr_standard"
BODY_TYPE"PLUMBING"
HDL_TAP"TRUE";
"B \NAC \NWC"6;
"S \NAC"
BN"4"71;
%"TAP"
"1","(-5750,5525)","2","mstr_standard","I253";
;
CDS_LIB"mstr_standard"
BODY_TYPE"PLUMBING"
HDL_TAP"TRUE";
"B \NAC \NWC"6;
"S \NAC"
BN"5"70;
%"TAP"
"1","(-5750,5425)","2","mstr_standard","I254";
;
CDS_LIB"mstr_standard"
BODY_TYPE"PLUMBING"
HDL_TAP"TRUE";
"B \NAC \NWC"6;
"S \NAC"
BN"6"69;
%"TAP"
"1","(-5750,5325)","2","mstr_standard","I255";
;
CDS_LIB"mstr_standard"
BODY_TYPE"PLUMBING"
HDL_TAP"TRUE";
"B \NAC \NWC"6;
"S \NAC"
BN"7"68;
%"TAP"
"1","(-5750,5225)","2","mstr_standard","I256";
;
CDS_LIB"mstr_standard"
BODY_TYPE"PLUMBING"
HDL_TAP"TRUE";
"B \NAC \NWC"6;
"S \NAC"
BN"8"67;
%"TAP"
"1","(-5750,5125)","2","mstr_standard","I257";
;
CDS_LIB"mstr_standard"
BODY_TYPE"PLUMBING"
HDL_TAP"TRUE";
"B \NAC \NWC"6;
"S \NAC"
BN"9"66;
%"TAP"
"1","(-5950,5575)","2","mstr_standard","I258";
;
CDS_LIB"mstr_standard"
BODY_TYPE"PLUMBING"
HDL_TAP"TRUE";
"B \NAC \NWC"5;
"S \NAC"
BN"4"61;
%"TAP"
"1","(-5950,5475)","2","mstr_standard","I259";
;
CDS_LIB"mstr_standard"
BODY_TYPE"PLUMBING"
HDL_TAP"TRUE";
"B \NAC \NWC"5;
"S \NAC"
BN"5"78;
%"TAP"
"1","(-5950,5375)","2","mstr_standard","I260";
;
CDS_LIB"mstr_standard"
BODY_TYPE"PLUMBING"
HDL_TAP"TRUE";
"B \NAC \NWC"5;
"S \NAC"
BN"6"76;
%"TAP"
"1","(-5950,5275)","2","mstr_standard","I261";
;
CDS_LIB"mstr_standard"
BODY_TYPE"PLUMBING"
HDL_TAP"TRUE";
"B \NAC \NWC"5;
"S \NAC"
BN"7"74;
%"TAP"
"1","(-5950,5175)","2","mstr_standard","I262";
;
CDS_LIB"mstr_standard"
BODY_TYPE"PLUMBING"
HDL_TAP"TRUE";
"B \NAC \NWC"5;
"S \NAC"
BN"8"72;
%"TAP"
"1","(-5750,4975)","2","mstr_standard","I263";
;
CDS_LIB"mstr_standard"
BODY_TYPE"PLUMBING"
HDL_TAP"TRUE";
"B \NAC \NWC"8;
"S \NAC"
BN"0"53;
%"TAP"
"1","(-5750,4875)","2","mstr_standard","I264";
;
CDS_LIB"mstr_standard"
BODY_TYPE"PLUMBING"
HDL_TAP"TRUE";
"B \NAC \NWC"8;
"S \NAC"
BN"1"51;
%"TAP"
"1","(-5750,4775)","2","mstr_standard","I265";
;
CDS_LIB"mstr_standard"
BODY_TYPE"PLUMBING"
HDL_TAP"TRUE";
"B \NAC \NWC"8;
"S \NAC"
BN"2"49;
%"TAP"
"1","(-5750,4675)","2","mstr_standard","I266";
;
CDS_LIB"mstr_standard"
BODY_TYPE"PLUMBING"
HDL_TAP"TRUE";
"B \NAC \NWC"8;
"S \NAC"
BN"3"47;
%"TAP"
"1","(-5950,5075)","2","mstr_standard","I267";
;
CDS_LIB"mstr_standard"
BODY_TYPE"PLUMBING"
HDL_TAP"TRUE";
"B \NAC \NWC"5;
"S \NAC"
BN"9"55;
%"TAP"
"1","(-5950,4925)","2","mstr_standard","I268";
;
CDS_LIB"mstr_standard"
BODY_TYPE"PLUMBING"
HDL_TAP"TRUE";
"B \NAC \NWC"7;
"S \NAC"
BN"0"59;
%"TAP"
"1","(-5950,4825)","2","mstr_standard","I269";
;
CDS_LIB"mstr_standard"
BODY_TYPE"PLUMBING"
HDL_TAP"TRUE";
"B \NAC \NWC"7;
"S \NAC"
BN"1"58;
%"TAP"
"1","(-5950,4725)","2","mstr_standard","I270";
;
CDS_LIB"mstr_standard"
BODY_TYPE"PLUMBING"
HDL_TAP"TRUE";
"B \NAC \NWC"7;
"S \NAC"
BN"2"57;
%"TAP"
"1","(-5950,4625)","2","mstr_standard","I271";
;
CDS_LIB"mstr_standard"
BODY_TYPE"PLUMBING"
HDL_TAP"TRUE";
"B \NAC \NWC"7;
"S \NAC"
BN"3"56;
%"TAP"
"1","(-5750,4575)","2","mstr_standard","I272";
;
CDS_LIB"mstr_standard"
BODY_TYPE"PLUMBING"
HDL_TAP"TRUE";
"B \NAC \NWC"8;
"S \NAC"
BN"4"45;
%"TAP"
"1","(-5750,4475)","2","mstr_standard","I273";
;
CDS_LIB"mstr_standard"
BODY_TYPE"PLUMBING"
HDL_TAP"TRUE";
"B \NAC \NWC"8;
"S \NAC"
BN"5"44;
%"TAP"
"1","(-5750,4375)","2","mstr_standard","I274";
;
CDS_LIB"mstr_standard"
BODY_TYPE"PLUMBING"
HDL_TAP"TRUE";
"B \NAC \NWC"8;
"S \NAC"
BN"6"43;
%"TAP"
"1","(-5750,4275)","2","mstr_standard","I275";
;
CDS_LIB"mstr_standard"
BODY_TYPE"PLUMBING"
HDL_TAP"TRUE";
"B \NAC \NWC"8;
"S \NAC"
BN"7"42;
%"TAP"
"1","(-5750,4175)","2","mstr_standard","I276";
;
CDS_LIB"mstr_standard"
BODY_TYPE"PLUMBING"
HDL_TAP"TRUE";
"B \NAC \NWC"8;
"S \NAC"
BN"8"41;
%"TAP"
"1","(-5950,4525)","2","mstr_standard","I277";
;
CDS_LIB"mstr_standard"
BODY_TYPE"PLUMBING"
HDL_TAP"TRUE";
"B \NAC \NWC"7;
"S \NAC"
BN"4"54;
%"TAP"
"1","(-5950,4425)","2","mstr_standard","I278";
;
CDS_LIB"mstr_standard"
BODY_TYPE"PLUMBING"
HDL_TAP"TRUE";
"B \NAC \NWC"7;
"S \NAC"
BN"5"52;
%"TAP"
"1","(-5950,4325)","2","mstr_standard","I279";
;
CDS_LIB"mstr_standard"
BODY_TYPE"PLUMBING"
HDL_TAP"TRUE";
"B \NAC \NWC"7;
"S \NAC"
BN"6"50;
%"TAP"
"1","(-5950,4225)","2","mstr_standard","I280";
;
CDS_LIB"mstr_standard"
BODY_TYPE"PLUMBING"
HDL_TAP"TRUE";
"B \NAC \NWC"7;
"S \NAC"
BN"7"48;
%"TAP"
"1","(-5950,4125)","2","mstr_standard","I281";
;
CDS_LIB"mstr_standard"
BODY_TYPE"PLUMBING"
HDL_TAP"TRUE";
"B \NAC \NWC"7;
"S \NAC"
BN"8"46;
%"TAP"
"1","(-5750,4075)","2","mstr_standard","I286";
;
CDS_LIB"mstr_standard"
BODY_TYPE"PLUMBING"
HDL_TAP"TRUE";
"B \NAC \NWC"8;
"S \NAC"
BN"9"25;
%"TAP"
"1","(-5950,4025)","2","mstr_standard","I287";
;
CDS_LIB"mstr_standard"
BODY_TYPE"PLUMBING"
HDL_TAP"TRUE";
"B \NAC \NWC"7;
"S \NAC"
BN"9"33;
%"TAP"
"1","(-5950,3825)","2","mstr_standard","I288";
;
CDS_LIB"mstr_standard"
BODY_TYPE"PLUMBING"
HDL_TAP"TRUE";
"B \NAC \NWC"9;
"S \NAC"
BN"1"38;
%"TAP"
"1","(-5950,3875)","2","mstr_standard","I289";
;
CDS_LIB"mstr_standard"
BODY_TYPE"PLUMBING"
HDL_TAP"TRUE";
"B \NAC \NWC"9;
"S \NAC"
BN"0"40;
%"TAP"
"1","(-5950,3775)","2","mstr_standard","I290";
;
CDS_LIB"mstr_standard"
BODY_TYPE"PLUMBING"
HDL_TAP"TRUE";
"B \NAC \NWC"9;
"S \NAC"
BN"2"36;
%"TAP"
"1","(-5950,3725)","2","mstr_standard","I291";
;
CDS_LIB"mstr_standard"
BODY_TYPE"PLUMBING"
HDL_TAP"TRUE";
"B \NAC \NWC"9;
"S \NAC"
BN"3"34;
%"TAP"
"1","(-5950,3675)","2","mstr_standard","I292";
;
CDS_LIB"mstr_standard"
BODY_TYPE"PLUMBING"
HDL_TAP"TRUE";
"B \NAC \NWC"9;
"S \NAC"
BN"4"32;
%"TAP"
"1","(-5950,3625)","2","mstr_standard","I293";
;
CDS_LIB"mstr_standard"
BODY_TYPE"PLUMBING"
HDL_TAP"TRUE";
"B \NAC \NWC"9;
"S \NAC"
BN"5"30;
%"TAP"
"1","(-5950,3575)","2","mstr_standard","I294";
;
CDS_LIB"mstr_standard"
BODY_TYPE"PLUMBING"
HDL_TAP"TRUE";
"B \NAC \NWC"9;
"S \NAC"
BN"6"28;
%"TAP"
"1","(-5950,3425)","2","mstr_standard","I295";
;
CDS_LIB"mstr_standard"
BODY_TYPE"PLUMBING"
HDL_TAP"TRUE";
"B \NAC \NWC"10;
"S \NAC"
BN"1"37;
%"TAP"
"1","(-5950,3475)","2","mstr_standard","I296";
;
CDS_LIB"mstr_standard"
BODY_TYPE"PLUMBING"
HDL_TAP"TRUE";
"B \NAC \NWC"10;
"S \NAC"
BN"0"39;
%"TAP"
"1","(-5950,3325)","2","mstr_standard","I297";
;
CDS_LIB"mstr_standard"
BODY_TYPE"PLUMBING"
HDL_TAP"TRUE";
"B \NAC \NWC"10;
"S \NAC"
BN"3"26;
%"TAP"
"1","(-5950,3375)","2","mstr_standard","I298";
;
CDS_LIB"mstr_standard"
BODY_TYPE"PLUMBING"
HDL_TAP"TRUE";
"B \NAC \NWC"10;
"S \NAC"
BN"2"35;
%"TAP"
"1","(-5950,3275)","2","mstr_standard","I299";
;
CDS_LIB"mstr_standard"
BODY_TYPE"PLUMBING"
HDL_TAP"TRUE";
"B \NAC \NWC"10;
"S \NAC"
BN"4"31;
%"TAP"
"1","(-5950,3225)","2","mstr_standard","I300";
;
CDS_LIB"mstr_standard"
BODY_TYPE"PLUMBING"
HDL_TAP"TRUE";
"B \NAC \NWC"10;
"S \NAC"
BN"5"29;
%"TAP"
"1","(-5950,3175)","2","mstr_standard","I301";
;
CDS_LIB"mstr_standard"
BODY_TYPE"PLUMBING"
HDL_TAP"TRUE";
"B \NAC \NWC"10;
"S \NAC"
BN"6"27;
%"Q_RES"
"1","(-6625,2175)","0","pure_quanta","I314";
;
LOCATION"R503"
$SEC"1"
CDS_SEC"1"
PACK_TYPE"0402LF"
TOLERANCE"1%"
VALUE"15"
MATERIAL"CHIP"
WATTAGE"1/16W"
CDS_LIB"pure_quanta"
PART_NUMBER"CS01502FB03";
"B"
$PN"2"12;
"A"
$PN"1"11;
END.
